FILE_TYPE = CONNECTIVITY;
{Allegro Design Entry HDL 17.4-2019 S026 (4007227) 1/17/2022}
"PAGE_NUMBER" = 19;
0"NC";
1"M_J_CPU0_SA_DQ<31:0>";
2"M_J_CPU0_SB_DQ<31:0>";
3"M_J_CPU0_SA_CB<7:0>";
4"M_J_CPU0_SB_CB<7:0>";
5"M_J_CPU0_SA_DQS_DP<9:0>";
6"M_J_CPU0_SA_DQS_DN<9:0>";
7"M_J_CPU0_SB_DQS_DP<9:0>";
8"M_J_CPU0_SB_DQS_DN<9:0>";
9"M_J_CPU0_SB_CA<6:0>";
10"M_J_CPU0_SA_CA<6:0>";
11"M_J_CPU0_ALERT_N";
12"M_J_CPU0_ALERT_R_N";
13"TP_M_J_CPU0_SA_TEST39J";
14"M_J_CPU0_CLK_DP<0>";
15"M_J_CPU0_CLK_DN<0>";
16"M_J_CPU0_SA_CS_N<0>";
17"M_J_CPU0_SA_PAR";
18"M_J_CPU0_SA_CS_N<1>";
19"M_J_CPU0_SA_RSP<0>";
20"M_J_CPU0_SB_CS_N<0>";
21"M_J_CPU0_SB_CS_N<1>";
22"M_J_CPU0_SB_RSP<0>";
23"M_J_CPU0_SB_PAR";
24"M_J_CPU0_RESET_N";
25"M_J_CPU0_SA_CA<5>";
26"M_J_CPU0_SA_CA<6>";
27"M_J_CPU0_SA_CA<0>";
28"M_J_CPU0_SA_CA<1>";
29"M_J_CPU0_SA_CA<2>";
30"M_J_CPU0_SA_CA<3>";
31"M_J_CPU0_SA_CA<4>";
32"M_J_CPU0_SB_CA<0>";
33"M_J_CPU0_SB_CA<1>";
34"M_J_CPU0_SB_CA<2>";
35"M_J_CPU0_SB_CA<3>";
36"M_J_CPU0_SB_CA<4>";
37"M_J_CPU0_SB_CA<5>";
38"M_J_CPU0_SB_CA<6>";
39"M_J_CPU0_SB_DQS_DN<9>";
40"M_J_CPU0_SB_DQS_DP<9>";
41"M_J_CPU0_SB_DQS_DN<4>";
42"M_J_CPU0_SB_DQS_DN<0>";
43"M_J_CPU0_SA_DQS_DN<9>";
44"M_J_CPU0_SB_DQS_DN<1>";
45"M_J_CPU0_SB_DQS_DN<2>";
46"M_J_CPU0_SB_DQS_DN<3>";
47"M_J_CPU0_SB_DQS_DN<5>";
48"M_J_CPU0_SB_DQS_DN<6>";
49"M_J_CPU0_SB_DQS_DN<7>";
50"M_J_CPU0_SB_DQS_DN<8>";
51"M_J_CPU0_SB_DQS_DP<5>";
52"M_J_CPU0_SB_DQS_DP<4>";
53"M_J_CPU0_SB_DQS_DP<6>";
54"M_J_CPU0_SB_DQS_DP<7>";
55"M_J_CPU0_SB_DQS_DP<8>";
56"M_J_CPU0_SA_DQS_DP<9>";
57"M_J_CPU0_SB_DQS_DP<0>";
58"M_J_CPU0_SB_DQS_DP<1>";
59"M_J_CPU0_SB_DQS_DP<2>";
60"M_J_CPU0_SB_DQS_DP<3>";
61"M_J_CPU0_SA_DQS_DN<4>";
62"M_J_CPU0_SA_DQS_DN<5>";
63"M_J_CPU0_SA_DQS_DN<7>";
64"M_J_CPU0_SA_DQS_DN<0>";
65"M_J_CPU0_SA_DQS_DN<1>";
66"M_J_CPU0_SA_DQS_DN<2>";
67"M_J_CPU0_SA_DQS_DN<3>";
68"M_J_CPU0_SA_DQS_DN<6>";
69"M_J_CPU0_SA_DQS_DN<8>";
70"M_J_CPU0_SA_DQS_DP<4>";
71"M_J_CPU0_SA_DQS_DP<8>";
72"M_J_CPU0_SA_DQS_DP<5>";
73"M_J_CPU0_SA_DQS_DP<6>";
74"M_J_CPU0_SA_DQS_DP<7>";
75"M_J_CPU0_SA_DQS_DP<0>";
76"M_J_CPU0_SA_DQS_DP<1>";
77"M_J_CPU0_SA_DQS_DP<2>";
78"M_J_CPU0_SA_DQS_DP<3>";
79"M_J_CPU0_SB_CB<0>";
80"M_J_CPU0_SB_CB<1>";
81"M_J_CPU0_SB_CB<2>";
82"M_J_CPU0_SB_CB<3>";
83"M_J_CPU0_SB_CB<4>";
84"M_J_CPU0_SB_CB<5>";
85"M_J_CPU0_SB_CB<6>";
86"M_J_CPU0_SB_CB<7>";
87"M_J_CPU0_SA_CB<0>";
88"M_J_CPU0_SA_CB<1>";
89"M_J_CPU0_SA_CB<2>";
90"M_J_CPU0_SA_CB<3>";
91"M_J_CPU0_SA_CB<4>";
92"M_J_CPU0_SA_CB<5>";
93"M_J_CPU0_SA_CB<6>";
94"M_J_CPU0_SA_CB<7>";
95"M_J_CPU0_SB_DQ<21>";
96"M_J_CPU0_SB_DQ<22>";
97"M_J_CPU0_SB_DQ<23>";
98"M_J_CPU0_SB_DQ<24>";
99"M_J_CPU0_SB_DQ<25>";
100"M_J_CPU0_SB_DQ<26>";
101"M_J_CPU0_SB_DQ<27>";
102"M_J_CPU0_SB_DQ<28>";
103"M_J_CPU0_SB_DQ<29>";
104"M_J_CPU0_SB_DQ<30>";
105"M_J_CPU0_SB_DQ<31>";
106"M_J_CPU0_SB_DQ<7>";
107"M_J_CPU0_SB_DQ<6>";
108"M_J_CPU0_SB_DQ<5>";
109"M_J_CPU0_SB_DQ<3>";
110"M_J_CPU0_SB_DQ<4>";
111"M_J_CPU0_SB_DQ<8>";
112"M_J_CPU0_SB_DQ<9>";
113"M_J_CPU0_SB_DQ<10>";
114"M_J_CPU0_SB_DQ<11>";
115"M_J_CPU0_SB_DQ<12>";
116"M_J_CPU0_SB_DQ<13>";
117"M_J_CPU0_SB_DQ<14>";
118"M_J_CPU0_SB_DQ<15>";
119"M_J_CPU0_SB_DQ<16>";
120"M_J_CPU0_SB_DQ<17>";
121"M_J_CPU0_SB_DQ<18>";
122"M_J_CPU0_SB_DQ<19>";
123"M_J_CPU0_SB_DQ<20>";
124"M_J_CPU0_SA_DQ<31>";
125"M_J_CPU0_SB_DQ<0>";
126"M_J_CPU0_SA_DQ<22>";
127"M_J_CPU0_SA_DQ<16>";
128"M_J_CPU0_SA_DQ<17>";
129"M_J_CPU0_SA_DQ<18>";
130"M_J_CPU0_SA_DQ<19>";
131"M_J_CPU0_SA_DQ<20>";
132"M_J_CPU0_SA_DQ<21>";
133"M_J_CPU0_SA_DQ<23>";
134"M_J_CPU0_SA_DQ<24>";
135"M_J_CPU0_SA_DQ<25>";
136"M_J_CPU0_SA_DQ<26>";
137"M_J_CPU0_SA_DQ<27>";
138"M_J_CPU0_SA_DQ<28>";
139"M_J_CPU0_SA_DQ<29>";
140"M_J_CPU0_SA_DQ<30>";
141"M_J_CPU0_SB_DQ<1>";
142"M_J_CPU0_SB_DQ<2>";
143"M_J_CPU0_SA_DQ<0>";
144"M_J_CPU0_SA_DQ<1>";
145"M_J_CPU0_SA_DQ<2>";
146"M_J_CPU0_SA_DQ<3>";
147"M_J_CPU0_SA_DQ<4>";
148"M_J_CPU0_SA_DQ<5>";
149"M_J_CPU0_SA_DQ<6>";
150"M_J_CPU0_SA_DQ<7>";
151"M_J_CPU0_SA_DQ<8>";
152"M_J_CPU0_SA_DQ<9>";
153"M_J_CPU0_SA_DQ<10>";
154"M_J_CPU0_SA_DQ<11>";
155"M_J_CPU0_SA_DQ<12>";
156"M_J_CPU0_SA_DQ<13>";
157"M_J_CPU0_SA_DQ<14>";
158"M_J_CPU0_SA_DQ<15>";
%"GENOA_SP5"
"10","(-4525,3625)","0","pure_quanta","I159";
;
LOCATION"U25"
$SEC"10"
CDS_SEC"10"
PART_TYPE"SMLF"
MATERIAL"IO"
VALUE"SOCKET6096_13568-001"
CDS_LIB"pure_quanta"
CDS_LMAN_SYM_OUTLINE"-650,2525,650,-2525"
NEEDS_NO_SIZE"TRUE"
PART_NUMBER"DGA^6000030";
"TEST39J"
$PN"BF18"13;
"MJB_DATA7"
$PN"CH18"106;
"MJB_DATA6"
$PN"CG16"107;
"MJB_DATA5"
$PN"CG17"108;
"MJB_DQS_H5"
$PN"CF18"51;
"MJB_DQS_L4"
$PN"BW17"41;
"MJB_DQS_L0"
$PN"CE16"42;
"MJA_DATA31"
$PN"AJ17"124;
"MJB_DATA0"
$PN"CB16"125;
"MJB_DATA3"
$PN"CD18"109;
"MJB_DATA4"
$PN"CF16"110;
"MJA_DQS_H4"
$PN"AL16"70;
"MJA_DQS_H8"
$PN"AG17"71;
"MJA_DQS_L4"
$PN"AM16"61;
"MJA_DQS_L5"
$PN"H18"62;
"MJA_DQS_L7"
$PN"Y18"63;
"MJA_DATA22"
$PN"AB16"126;
"MJA_CA5"
$PN"BB16"25;
"MJA_CA6"
$PN"BB18"26;
"MJ0_CLK_H"
$PN"BC16"14;
"MJ0_CLK_L"
$PN"BD16"15;
"MJ1_CLK_H"
$PN"BF16"0;
"MJ1_CLK_L"
$PN"BG16"0;
"MJA0_CS_L0"
$PN"AU16"16;
"MJA0_CS_L1"
$PN"AV18"18;
"MJA0_RSP_L"
$PN"BN17"19;
"MJA1_CS_L0"
$PN"AV16"0;
"MJA1_CS_L1"
$PN"AW17"0;
"MJA1_RSP_L"
$PN"BP18"0;
"MJA_CA0"
$PN"AW16"27;
"MJA_CA1"
$PN"AY16"28;
"MJA_CA2"
$PN"AY18"29;
"MJA_CA3"
$PN"BA17"30;
"MJA_CA4"
$PN"BA16"31;
"MJA_CHECK0"
$PN"AJ16"87;
"MJA_CHECK1"
$PN"AK18"88;
"MJA_CHECK2"
$PN"AK16"89;
"MJA_CHECK3"
$PN"AL17"90;
"MJA_CHECK4"
$PN"AN16"91;
"MJA_CHECK5"
$PN"AP18"92;
"MJA_CHECK6"
$PN"AP16"93;
"MJA_CHECK7"
$PN"AR17"94;
"MJA_DATA0"
$PN"E16"143;
"MJA_DATA1"
$PN"F18"144;
"MJA_DATA2"
$PN"F16"145;
"MJA_DATA3"
$PN"G17"146;
"MJA_DATA4"
$PN"J16"147;
"MJA_DATA5"
$PN"K18"148;
"MJA_DATA6"
$PN"K16"149;
"MJA_DATA7"
$PN"L17"150;
"MJA_DATA8"
$PN"L16"151;
"MJA_DATA9"
$PN"M18"152;
"MJA_DATA10"
$PN"M16"153;
"MJA_DATA11"
$PN"N17"154;
"MJA_DATA12"
$PN"R16"155;
"MJA_DATA13"
$PN"T18"156;
"MJA_DATA14"
$PN"T16"157;
"MJA_DATA15"
$PN"U17"158;
"MJA_DATA16"
$PN"U16"127;
"MJA_DATA17"
$PN"V18"128;
"MJA_DATA18"
$PN"V16"129;
"MJA_DATA19"
$PN"W17"130;
"MJA_DATA20"
$PN"AA16"131;
"MJA_DATA21"
$PN"AB18"132;
"MJA_DATA23"
$PN"AC17"133;
"MJA_DATA24"
$PN"AC16"134;
"MJA_DATA25"
$PN"AD18"135;
"MJA_DATA26"
$PN"AD16"136;
"MJA_DATA27"
$PN"AE17"137;
"MJA_DATA28"
$PN"AG16"138;
"MJA_DATA29"
$PN"AH18"139;
"MJA_DATA30"
$PN"AH16"140;
"MJA_DQS_H0"
$PN"G16"75;
"MJA_DQS_H1"
$PN"N16"76;
"MJA_DQS_H2"
$PN"W16"77;
"MJA_DQS_H3"
$PN"AE16"78;
"MJA_DQS_H5"
$PN"J17"72;
"MJA_DQS_H6"
$PN"R17"73;
"MJA_DQS_H7"
$PN"AA17"74;
"MJA_DQS_H9"
$PN"AN17"56;
"MJA_DQS_L0"
$PN"H16"64;
"MJA_DQS_L1"
$PN"P16"65;
"MJA_DQS_L2"
$PN"Y16"66;
"MJA_DQS_L3"
$PN"AF16"67;
"MJA_DQS_L6"
$PN"P18"68;
"MJA_DQS_L8"
$PN"AF18"69;
"MJA_DQS_L9"
$PN"AM18"43;
"MJA_PAR"
$PN"BC17"17;
"MJB0_CS_L0"
$PN"BM18"20;
"MJB0_CS_L1"
$PN"BN16"21;
"MJB0_RSP_L"
$PN"BP16"22;
"MJB1_CS_L0"
$PN"BL16"0;
"MJB1_CS_L1"
$PN"BM16"0;
"MJB1_RSP_L"
$PN"BR16"0;
"MJB_CA0"
$PN"BG17"32;
"MJB_CA1"
$PN"BH18"33;
"MJB_CA2"
$PN"BH16"34;
"MJB_CA3"
$PN"BJ16"35;
"MJB_CA4"
$PN"BJ17"36;
"MJB_CA5"
$PN"BK18"37;
"MJB_CA6"
$PN"BK16"38;
"MJB_CHECK0"
$PN"BY16"79;
"MJB_CHECK1"
$PN"CA17"80;
"MJB_CHECK2"
$PN"CA16"81;
"MJB_CHECK3"
$PN"CB18"82;
"MJB_CHECK4"
$PN"BT16"83;
"MJB_CHECK5"
$PN"BU17"84;
"MJB_CHECK6"
$PN"BU16"85;
"MJB_CHECK7"
$PN"BV18"86;
"MJB_DATA1"
$PN"CC17"141;
"MJB_DATA2"
$PN"CC16"142;
"MJB_DATA8"
$PN"CH16"111;
"MJB_DATA9"
$PN"CJ17"112;
"MJB_DATA10"
$PN"CJ16"113;
"MJB_DATA11"
$PN"CK18"114;
"MJB_DATA12"
$PN"CM16"115;
"MJB_DATA13"
$PN"CN17"116;
"MJB_DATA14"
$PN"CN16"117;
"MJB_DATA15"
$PN"CP18"118;
"MJB_DATA16"
$PN"CP16"119;
"MJB_DATA17"
$PN"CR17"120;
"MJB_DATA18"
$PN"CR16"121;
"MJB_DATA19"
$PN"CT18"122;
"MJB_DATA20"
$PN"CV16"123;
"MJB_DATA21"
$PN"CW17"95;
"MJB_DATA22"
$PN"CW16"96;
"MJB_DATA23"
$PN"CY18"97;
"MJB_DATA24"
$PN"CY16"98;
"MJB_DATA25"
$PN"DA17"99;
"MJB_DATA26"
$PN"DA16"100;
"MJB_DATA27"
$PN"DB18"101;
"MJB_DATA28"
$PN"DD16"102;
"MJB_DATA29"
$PN"DE17"103;
"MJB_DATA30"
$PN"DE16"104;
"MJB_DATA31"
$PN"DF16"105;
"MJB_DQS_H0"
$PN"CD16"57;
"MJB_DQS_H1"
$PN"CK16"58;
"MJB_DQS_H2"
$PN"CT16"59;
"MJB_DQS_H3"
$PN"DB16"60;
"MJB_DQS_H4"
$PN"BY18"52;
"MJB_DQS_H6"
$PN"CM18"53;
"MJB_DQS_H7"
$PN"CV18"54;
"MJB_DQS_H8"
$PN"DD18"55;
"MJB_DQS_H9"
$PN"BV16"40;
"MJB_DQS_L1"
$PN"CL16"44;
"MJB_DQS_L2"
$PN"CU16"45;
"MJB_DQS_L3"
$PN"DC16"46;
"MJB_DQS_L5"
$PN"CE17"47;
"MJB_DQS_L6"
$PN"CL17"48;
"MJB_DQS_L7"
$PN"CU17"49;
"MJB_DQS_L8"
$PN"DC17"50;
"MJB_DQS_L9"
$PN"BW16"39;
"MJB_PAR"
$PN"BL17"23;
"MJ_ALERT_L"
$PN"AT18"12;
"MJ_RESET_L"
$PN"AU17"24;
%"TAP"
"1","(-3250,5900)","0","mstr_standard","I162";
;
CDS_LIB"mstr_standard"
BODY_TYPE"PLUMBING"
HDL_TAP"TRUE";
"B \NAC \NWC"1;
"S \NAC"
BN"2"145;
%"TAP"
"1","(-3250,6000)","0","mstr_standard","I163";
;
CDS_LIB"mstr_standard"
BODY_TYPE"PLUMBING"
HDL_TAP"TRUE";
"B \NAC \NWC"1;
"S \NAC"
BN"0"143;
%"TAP"
"1","(-3250,5950)","0","mstr_standard","I164";
;
CDS_LIB"mstr_standard"
BODY_TYPE"PLUMBING"
HDL_TAP"TRUE";
"B \NAC \NWC"1;
"S \NAC"
BN"1"144;
%"TAP"
"1","(-3250,5850)","0","mstr_standard","I165";
;
CDS_LIB"mstr_standard"
BODY_TYPE"PLUMBING"
HDL_TAP"TRUE";
"B \NAC \NWC"1;
"S \NAC"
BN"3"146;
%"TAP"
"1","(-3250,5800)","0","mstr_standard","I166";
;
CDS_LIB"mstr_standard"
BODY_TYPE"PLUMBING"
HDL_TAP"TRUE";
"B \NAC \NWC"1;
"S \NAC"
BN"4"147;
%"TAP"
"1","(-3250,5700)","0","mstr_standard","I167";
;
CDS_LIB"mstr_standard"
BODY_TYPE"PLUMBING"
HDL_TAP"TRUE";
"B \NAC \NWC"1;
"S \NAC"
BN"6"149;
%"TAP"
"1","(-3250,5750)","0","mstr_standard","I168";
;
CDS_LIB"mstr_standard"
BODY_TYPE"PLUMBING"
HDL_TAP"TRUE";
"B \NAC \NWC"1;
"S \NAC"
BN"5"148;
%"TAP"
"1","(-3250,5650)","0","mstr_standard","I169";
;
CDS_LIB"mstr_standard"
BODY_TYPE"PLUMBING"
HDL_TAP"TRUE";
"B \NAC \NWC"1;
"S \NAC"
BN"7"150;
%"TAP"
"1","(-3250,5550)","0","mstr_standard","I170";
;
CDS_LIB"mstr_standard"
BODY_TYPE"PLUMBING"
HDL_TAP"TRUE";
"B \NAC \NWC"1;
"S \NAC"
BN"8"151;
%"TAP"
"1","(-3250,5500)","0","mstr_standard","I171";
;
CDS_LIB"mstr_standard"
BODY_TYPE"PLUMBING"
HDL_TAP"TRUE";
"B \NAC \NWC"1;
"S \NAC"
BN"9"152;
%"TAP"
"1","(-3250,5450)","0","mstr_standard","I172";
;
CDS_LIB"mstr_standard"
BODY_TYPE"PLUMBING"
HDL_TAP"TRUE";
"B \NAC \NWC"1;
"S \NAC"
BN"10"153;
%"TAP"
"1","(-3250,5400)","0","mstr_standard","I173";
;
CDS_LIB"mstr_standard"
BODY_TYPE"PLUMBING"
HDL_TAP"TRUE";
"B \NAC \NWC"1;
"S \NAC"
BN"11"154;
%"TAP"
"1","(-3250,5350)","0","mstr_standard","I174";
;
CDS_LIB"mstr_standard"
BODY_TYPE"PLUMBING"
HDL_TAP"TRUE";
"B \NAC \NWC"1;
"S \NAC"
BN"12"155;
%"TAP"
"1","(-3250,5300)","0","mstr_standard","I175";
;
CDS_LIB"mstr_standard"
BODY_TYPE"PLUMBING"
HDL_TAP"TRUE";
"B \NAC \NWC"1;
"S \NAC"
BN"13"156;
%"TAP"
"1","(-3250,5250)","0","mstr_standard","I176";
;
CDS_LIB"mstr_standard"
BODY_TYPE"PLUMBING"
HDL_TAP"TRUE";
"B \NAC \NWC"1;
"S \NAC"
BN"14"157;
%"TAP"
"1","(-3250,5200)","0","mstr_standard","I177";
;
CDS_LIB"mstr_standard"
BODY_TYPE"PLUMBING"
HDL_TAP"TRUE";
"B \NAC \NWC"1;
"S \NAC"
BN"15"158;
%"TAP"
"1","(-3250,5000)","0","mstr_standard","I178";
;
CDS_LIB"mstr_standard"
BODY_TYPE"PLUMBING"
HDL_TAP"TRUE";
"B \NAC \NWC"1;
"S \NAC"
BN"18"129;
%"TAP"
"1","(-3250,5100)","0","mstr_standard","I179";
;
CDS_LIB"mstr_standard"
BODY_TYPE"PLUMBING"
HDL_TAP"TRUE";
"B \NAC \NWC"1;
"S \NAC"
BN"16"127;
%"TAP"
"1","(-3250,5050)","0","mstr_standard","I180";
;
CDS_LIB"mstr_standard"
BODY_TYPE"PLUMBING"
HDL_TAP"TRUE";
"B \NAC \NWC"1;
"S \NAC"
BN"17"128;
%"TAP"
"1","(-3250,4950)","0","mstr_standard","I181";
;
CDS_LIB"mstr_standard"
BODY_TYPE"PLUMBING"
HDL_TAP"TRUE";
"B \NAC \NWC"1;
"S \NAC"
BN"19"130;
%"TAP"
"1","(-3250,4900)","0","mstr_standard","I182";
;
CDS_LIB"mstr_standard"
BODY_TYPE"PLUMBING"
HDL_TAP"TRUE";
"B \NAC \NWC"1;
"S \NAC"
BN"20"131;
%"TAP"
"1","(-3250,4800)","0","mstr_standard","I183";
;
CDS_LIB"mstr_standard"
BODY_TYPE"PLUMBING"
HDL_TAP"TRUE";
"B \NAC \NWC"1;
"S \NAC"
BN"22"126;
%"TAP"
"1","(-3250,4850)","0","mstr_standard","I184";
;
CDS_LIB"mstr_standard"
BODY_TYPE"PLUMBING"
HDL_TAP"TRUE";
"B \NAC \NWC"1;
"S \NAC"
BN"21"132;
%"TAP"
"1","(-3250,4750)","0","mstr_standard","I185";
;
CDS_LIB"mstr_standard"
BODY_TYPE"PLUMBING"
HDL_TAP"TRUE";
"B \NAC \NWC"1;
"S \NAC"
BN"23"133;
%"TAP"
"1","(-3250,4650)","0","mstr_standard","I186";
;
CDS_LIB"mstr_standard"
BODY_TYPE"PLUMBING"
HDL_TAP"TRUE";
"B \NAC \NWC"1;
"S \NAC"
BN"24"134;
%"TAP"
"1","(-3250,4500)","0","mstr_standard","I187";
;
CDS_LIB"mstr_standard"
BODY_TYPE"PLUMBING"
HDL_TAP"TRUE";
"B \NAC \NWC"1;
"S \NAC"
BN"27"137;
%"TAP"
"1","(-3250,4550)","0","mstr_standard","I188";
;
CDS_LIB"mstr_standard"
BODY_TYPE"PLUMBING"
HDL_TAP"TRUE";
"B \NAC \NWC"1;
"S \NAC"
BN"26"136;
%"TAP"
"1","(-3250,4600)","0","mstr_standard","I189";
;
CDS_LIB"mstr_standard"
BODY_TYPE"PLUMBING"
HDL_TAP"TRUE";
"B \NAC \NWC"1;
"S \NAC"
BN"25"135;
%"TAP"
"1","(-3250,4450)","0","mstr_standard","I190";
;
CDS_LIB"mstr_standard"
BODY_TYPE"PLUMBING"
HDL_TAP"TRUE";
"B \NAC \NWC"1;
"S \NAC"
BN"28"138;
%"TAP"
"1","(-3250,4400)","0","mstr_standard","I191";
;
CDS_LIB"mstr_standard"
BODY_TYPE"PLUMBING"
HDL_TAP"TRUE";
"B \NAC \NWC"1;
"S \NAC"
BN"29"139;
%"TAP"
"1","(-3250,4300)","0","mstr_standard","I192";
;
CDS_LIB"mstr_standard"
BODY_TYPE"PLUMBING"
HDL_TAP"TRUE";
"B \NAC \NWC"1;
"S \NAC"
BN"31"124;
%"TAP"
"1","(-3250,4350)","0","mstr_standard","I193";
;
CDS_LIB"mstr_standard"
BODY_TYPE"PLUMBING"
HDL_TAP"TRUE";
"B \NAC \NWC"1;
"S \NAC"
BN"30"140;
%"TAP"
"1","(-3250,4200)","0","mstr_standard","I194";
;
CDS_LIB"mstr_standard"
BODY_TYPE"PLUMBING"
HDL_TAP"TRUE";
"B \NAC \NWC"2;
"S \NAC"
BN"0"125;
%"TAP"
"1","(-3250,4150)","0","mstr_standard","I195";
;
CDS_LIB"mstr_standard"
BODY_TYPE"PLUMBING"
HDL_TAP"TRUE";
"B \NAC \NWC"2;
"S \NAC"
BN"1"141;
%"TAP"
"1","(-3250,4100)","0","mstr_standard","I196";
;
CDS_LIB"mstr_standard"
BODY_TYPE"PLUMBING"
HDL_TAP"TRUE";
"B \NAC \NWC"2;
"S \NAC"
BN"2"142;
%"TAP"
"1","(-3250,4050)","0","mstr_standard","I198";
;
CDS_LIB"mstr_standard"
BODY_TYPE"PLUMBING"
HDL_TAP"TRUE";
"B \NAC \NWC"2;
"S \NAC"
BN"3"109;
%"TAP"
"1","(-3250,4000)","0","mstr_standard","I199";
;
CDS_LIB"mstr_standard"
BODY_TYPE"PLUMBING"
HDL_TAP"TRUE";
"B \NAC \NWC"2;
"S \NAC"
BN"4"110;
%"TAP"
"1","(-3250,3850)","0","mstr_standard","I200";
;
CDS_LIB"mstr_standard"
BODY_TYPE"PLUMBING"
HDL_TAP"TRUE";
"B \NAC \NWC"2;
"S \NAC"
BN"7"106;
%"TAP"
"1","(-3250,3900)","0","mstr_standard","I201";
;
CDS_LIB"mstr_standard"
BODY_TYPE"PLUMBING"
HDL_TAP"TRUE";
"B \NAC \NWC"2;
"S \NAC"
BN"6"107;
%"TAP"
"1","(-3250,3950)","0","mstr_standard","I202";
;
CDS_LIB"mstr_standard"
BODY_TYPE"PLUMBING"
HDL_TAP"TRUE";
"B \NAC \NWC"2;
"S \NAC"
BN"5"108;
%"TAP"
"1","(-3250,3750)","0","mstr_standard","I203";
;
CDS_LIB"mstr_standard"
BODY_TYPE"PLUMBING"
HDL_TAP"TRUE";
"B \NAC \NWC"2;
"S \NAC"
BN"8"111;
%"TAP"
"1","(-3250,3700)","0","mstr_standard","I204";
;
CDS_LIB"mstr_standard"
BODY_TYPE"PLUMBING"
HDL_TAP"TRUE";
"B \NAC \NWC"2;
"S \NAC"
BN"9"112;
%"TAP"
"1","(-3250,3650)","0","mstr_standard","I205";
;
CDS_LIB"mstr_standard"
BODY_TYPE"PLUMBING"
HDL_TAP"TRUE";
"B \NAC \NWC"2;
"S \NAC"
BN"10"113;
%"TAP"
"1","(-3250,3600)","0","mstr_standard","I206";
;
CDS_LIB"mstr_standard"
BODY_TYPE"PLUMBING"
HDL_TAP"TRUE";
"B \NAC \NWC"2;
"S \NAC"
BN"11"114;
%"TAP"
"1","(-3250,3500)","0","mstr_standard","I207";
;
CDS_LIB"mstr_standard"
BODY_TYPE"PLUMBING"
HDL_TAP"TRUE";
"B \NAC \NWC"2;
"S \NAC"
BN"13"116;
%"TAP"
"1","(-3250,3550)","0","mstr_standard","I208";
;
CDS_LIB"mstr_standard"
BODY_TYPE"PLUMBING"
HDL_TAP"TRUE";
"B \NAC \NWC"2;
"S \NAC"
BN"12"115;
%"TAP"
"1","(-3250,3400)","0","mstr_standard","I209";
;
CDS_LIB"mstr_standard"
BODY_TYPE"PLUMBING"
HDL_TAP"TRUE";
"B \NAC \NWC"2;
"S \NAC"
BN"15"118;
%"TAP"
"1","(-3250,3450)","0","mstr_standard","I210";
;
CDS_LIB"mstr_standard"
BODY_TYPE"PLUMBING"
HDL_TAP"TRUE";
"B \NAC \NWC"2;
"S \NAC"
BN"14"117;
%"TAP"
"1","(-3250,3250)","0","mstr_standard","I211";
;
CDS_LIB"mstr_standard"
BODY_TYPE"PLUMBING"
HDL_TAP"TRUE";
"B \NAC \NWC"2;
"S \NAC"
BN"17"120;
%"TAP"
"1","(-3250,3300)","0","mstr_standard","I212";
;
CDS_LIB"mstr_standard"
BODY_TYPE"PLUMBING"
HDL_TAP"TRUE";
"B \NAC \NWC"2;
"S \NAC"
BN"16"119;
%"TAP"
"1","(-3250,3200)","0","mstr_standard","I213";
;
CDS_LIB"mstr_standard"
BODY_TYPE"PLUMBING"
HDL_TAP"TRUE";
"B \NAC \NWC"2;
"S \NAC"
BN"18"121;
%"TAP"
"1","(-3250,3100)","0","mstr_standard","I214";
;
CDS_LIB"mstr_standard"
BODY_TYPE"PLUMBING"
HDL_TAP"TRUE";
"B \NAC \NWC"2;
"S \NAC"
BN"20"123;
%"TAP"
"1","(-3250,3150)","0","mstr_standard","I215";
;
CDS_LIB"mstr_standard"
BODY_TYPE"PLUMBING"
HDL_TAP"TRUE";
"B \NAC \NWC"2;
"S \NAC"
BN"19"122;
%"TAP"
"1","(-3250,2950)","0","mstr_standard","I216";
;
CDS_LIB"mstr_standard"
BODY_TYPE"PLUMBING"
HDL_TAP"TRUE";
"B \NAC \NWC"2;
"S \NAC"
BN"23"97;
%"TAP"
"1","(-3250,3000)","0","mstr_standard","I217";
;
CDS_LIB"mstr_standard"
BODY_TYPE"PLUMBING"
HDL_TAP"TRUE";
"B \NAC \NWC"2;
"S \NAC"
BN"22"96;
%"TAP"
"1","(-3250,3050)","0","mstr_standard","I218";
;
CDS_LIB"mstr_standard"
BODY_TYPE"PLUMBING"
HDL_TAP"TRUE";
"B \NAC \NWC"2;
"S \NAC"
BN"21"95;
%"TAP"
"1","(-3250,2850)","0","mstr_standard","I219";
;
CDS_LIB"mstr_standard"
BODY_TYPE"PLUMBING"
HDL_TAP"TRUE";
"B \NAC \NWC"2;
"S \NAC"
BN"24"98;
%"TAP"
"1","(-3250,2800)","0","mstr_standard","I220";
;
CDS_LIB"mstr_standard"
BODY_TYPE"PLUMBING"
HDL_TAP"TRUE";
"B \NAC \NWC"2;
"S \NAC"
BN"25"99;
%"TAP"
"1","(-3250,2750)","0","mstr_standard","I221";
;
CDS_LIB"mstr_standard"
BODY_TYPE"PLUMBING"
HDL_TAP"TRUE";
"B \NAC \NWC"2;
"S \NAC"
BN"26"100;
%"TAP"
"1","(-3250,2700)","0","mstr_standard","I222";
;
CDS_LIB"mstr_standard"
BODY_TYPE"PLUMBING"
HDL_TAP"TRUE";
"B \NAC \NWC"2;
"S \NAC"
BN"27"101;
%"TAP"
"1","(-3250,2650)","0","mstr_standard","I223";
;
CDS_LIB"mstr_standard"
BODY_TYPE"PLUMBING"
HDL_TAP"TRUE";
"B \NAC \NWC"2;
"S \NAC"
BN"28"102;
%"TAP"
"1","(-3250,2600)","0","mstr_standard","I224";
;
CDS_LIB"mstr_standard"
BODY_TYPE"PLUMBING"
HDL_TAP"TRUE";
"B \NAC \NWC"2;
"S \NAC"
BN"29"103;
%"TAP"
"1","(-3250,2550)","0","mstr_standard","I225";
;
CDS_LIB"mstr_standard"
BODY_TYPE"PLUMBING"
HDL_TAP"TRUE";
"B \NAC \NWC"2;
"S \NAC"
BN"30"104;
%"TAP"
"1","(-3250,2500)","0","mstr_standard","I226";
;
CDS_LIB"mstr_standard"
BODY_TYPE"PLUMBING"
HDL_TAP"TRUE";
"B \NAC \NWC"2;
"S \NAC"
BN"31"105;
%"TAP"
"1","(-3250,2400)","0","mstr_standard","I227";
;
CDS_LIB"mstr_standard"
BODY_TYPE"PLUMBING"
HDL_TAP"TRUE";
"B \NAC \NWC"3;
"S \NAC"
BN"0"87;
%"TAP"
"1","(-3250,2350)","0","mstr_standard","I228";
;
CDS_LIB"mstr_standard"
BODY_TYPE"PLUMBING"
HDL_TAP"TRUE";
"B \NAC \NWC"3;
"S \NAC"
BN"1"88;
%"TAP"
"1","(-3250,2300)","0","mstr_standard","I229";
;
CDS_LIB"mstr_standard"
BODY_TYPE"PLUMBING"
HDL_TAP"TRUE";
"B \NAC \NWC"3;
"S \NAC"
BN"2"89;
%"TAP"
"1","(-3250,2250)","0","mstr_standard","I230";
;
CDS_LIB"mstr_standard"
BODY_TYPE"PLUMBING"
HDL_TAP"TRUE";
"B \NAC \NWC"3;
"S \NAC"
BN"3"90;
%"TAP"
"1","(-3250,2200)","0","mstr_standard","I231";
;
CDS_LIB"mstr_standard"
BODY_TYPE"PLUMBING"
HDL_TAP"TRUE";
"B \NAC \NWC"3;
"S \NAC"
BN"4"91;
%"TAP"
"1","(-3250,2100)","0","mstr_standard","I232";
;
CDS_LIB"mstr_standard"
BODY_TYPE"PLUMBING"
HDL_TAP"TRUE";
"B \NAC \NWC"3;
"S \NAC"
BN"6"93;
%"TAP"
"1","(-3250,2150)","0","mstr_standard","I233";
;
CDS_LIB"mstr_standard"
BODY_TYPE"PLUMBING"
HDL_TAP"TRUE";
"B \NAC \NWC"3;
"S \NAC"
BN"5"92;
%"TAP"
"1","(-3250,2050)","0","mstr_standard","I234";
;
CDS_LIB"mstr_standard"
BODY_TYPE"PLUMBING"
HDL_TAP"TRUE";
"B \NAC \NWC"3;
"S \NAC"
BN"7"94;
%"TAP"
"1","(-3250,1950)","0","mstr_standard","I236";
;
CDS_LIB"mstr_standard"
BODY_TYPE"PLUMBING"
HDL_TAP"TRUE";
"B \NAC \NWC"4;
"S \NAC"
BN"0"79;
%"TAP"
"1","(-3250,1800)","0","mstr_standard","I237";
;
CDS_LIB"mstr_standard"
BODY_TYPE"PLUMBING"
HDL_TAP"TRUE";
"B \NAC \NWC"4;
"S \NAC"
BN"3"82;
%"TAP"
"1","(-3250,1900)","0","mstr_standard","I238";
;
CDS_LIB"mstr_standard"
BODY_TYPE"PLUMBING"
HDL_TAP"TRUE";
"B \NAC \NWC"4;
"S \NAC"
BN"1"80;
%"TAP"
"1","(-3250,1850)","0","mstr_standard","I239";
;
CDS_LIB"mstr_standard"
BODY_TYPE"PLUMBING"
HDL_TAP"TRUE";
"B \NAC \NWC"4;
"S \NAC"
BN"2"81;
%"TAP"
"1","(-3250,1750)","0","mstr_standard","I240";
;
CDS_LIB"mstr_standard"
BODY_TYPE"PLUMBING"
HDL_TAP"TRUE";
"B \NAC \NWC"4;
"S \NAC"
BN"4"83;
%"TAP"
"1","(-3250,1700)","0","mstr_standard","I241";
;
CDS_LIB"mstr_standard"
BODY_TYPE"PLUMBING"
HDL_TAP"TRUE";
"B \NAC \NWC"4;
"S \NAC"
BN"5"84;
%"TAP"
"1","(-3250,1650)","0","mstr_standard","I242";
;
CDS_LIB"mstr_standard"
BODY_TYPE"PLUMBING"
HDL_TAP"TRUE";
"B \NAC \NWC"4;
"S \NAC"
BN"6"85;
%"TAP"
"1","(-3250,1600)","0","mstr_standard","I243";
;
CDS_LIB"mstr_standard"
BODY_TYPE"PLUMBING"
HDL_TAP"TRUE";
"B \NAC \NWC"4;
"S \NAC"
BN"7"86;
%"TAP"
"1","(-5675,5900)","2","mstr_standard","I244";
;
CDS_LIB"mstr_standard"
BODY_TYPE"PLUMBING"
HDL_TAP"TRUE";
"B \NAC \NWC"5;
"S \NAC"
BN"1"76;
%"TAP"
"1","(-5675,6000)","2","mstr_standard","I245";
;
CDS_LIB"mstr_standard"
BODY_TYPE"PLUMBING"
HDL_TAP"TRUE";
"B \NAC \NWC"5;
"S \NAC"
BN"0"75;
%"TAP"
"1","(-5675,5800)","2","mstr_standard","I246";
;
CDS_LIB"mstr_standard"
BODY_TYPE"PLUMBING"
HDL_TAP"TRUE";
"B \NAC \NWC"5;
"S \NAC"
BN"2"77;
%"TAP"
"1","(-5675,5700)","2","mstr_standard","I247";
;
CDS_LIB"mstr_standard"
BODY_TYPE"PLUMBING"
HDL_TAP"TRUE";
"B \NAC \NWC"5;
"S \NAC"
BN"3"78;
%"TAP"
"1","(-5875,5950)","2","mstr_standard","I248";
;
CDS_LIB"mstr_standard"
BODY_TYPE"PLUMBING"
HDL_TAP"TRUE";
"B \NAC \NWC"6;
"S \NAC"
BN"0"64;
%"TAP"
"1","(-5875,5650)","2","mstr_standard","I249";
;
CDS_LIB"mstr_standard"
BODY_TYPE"PLUMBING"
HDL_TAP"TRUE";
"B \NAC \NWC"6;
"S \NAC"
BN"3"67;
%"TAP"
"1","(-5875,5750)","2","mstr_standard","I250";
;
CDS_LIB"mstr_standard"
BODY_TYPE"PLUMBING"
HDL_TAP"TRUE";
"B \NAC \NWC"6;
"S \NAC"
BN"2"66;
%"TAP"
"1","(-5875,5850)","2","mstr_standard","I251";
;
CDS_LIB"mstr_standard"
BODY_TYPE"PLUMBING"
HDL_TAP"TRUE";
"B \NAC \NWC"6;
"S \NAC"
BN"1"65;
%"TAP"
"1","(-5675,5600)","2","mstr_standard","I252";
;
CDS_LIB"mstr_standard"
BODY_TYPE"PLUMBING"
HDL_TAP"TRUE";
"B \NAC \NWC"5;
"S \NAC"
BN"4"70;
%"TAP"
"1","(-5675,5500)","2","mstr_standard","I253";
;
CDS_LIB"mstr_standard"
BODY_TYPE"PLUMBING"
HDL_TAP"TRUE";
"B \NAC \NWC"5;
"S \NAC"
BN"5"72;
%"TAP"
"1","(-5675,5400)","2","mstr_standard","I254";
;
CDS_LIB"mstr_standard"
BODY_TYPE"PLUMBING"
HDL_TAP"TRUE";
"B \NAC \NWC"5;
"S \NAC"
BN"6"73;
%"TAP"
"1","(-5675,5300)","2","mstr_standard","I255";
;
CDS_LIB"mstr_standard"
BODY_TYPE"PLUMBING"
HDL_TAP"TRUE";
"B \NAC \NWC"5;
"S \NAC"
BN"7"74;
%"TAP"
"1","(-5675,5200)","2","mstr_standard","I256";
;
CDS_LIB"mstr_standard"
BODY_TYPE"PLUMBING"
HDL_TAP"TRUE";
"B \NAC \NWC"5;
"S \NAC"
BN"8"71;
%"TAP"
"1","(-5875,5450)","2","mstr_standard","I257";
;
CDS_LIB"mstr_standard"
BODY_TYPE"PLUMBING"
HDL_TAP"TRUE";
"B \NAC \NWC"6;
"S \NAC"
BN"5"62;
%"TAP"
"1","(-5875,5550)","2","mstr_standard","I258";
;
CDS_LIB"mstr_standard"
BODY_TYPE"PLUMBING"
HDL_TAP"TRUE";
"B \NAC \NWC"6;
"S \NAC"
BN"4"61;
%"TAP"
"1","(-5875,5150)","2","mstr_standard","I259";
;
CDS_LIB"mstr_standard"
BODY_TYPE"PLUMBING"
HDL_TAP"TRUE";
"B \NAC \NWC"6;
"S \NAC"
BN"8"69;
%"TAP"
"1","(-5875,5350)","2","mstr_standard","I260";
;
CDS_LIB"mstr_standard"
BODY_TYPE"PLUMBING"
HDL_TAP"TRUE";
"B \NAC \NWC"6;
"S \NAC"
BN"6"68;
%"TAP"
"1","(-5875,5250)","2","mstr_standard","I261";
;
CDS_LIB"mstr_standard"
BODY_TYPE"PLUMBING"
HDL_TAP"TRUE";
"B \NAC \NWC"6;
"S \NAC"
BN"7"63;
%"TAP"
"1","(-5675,4950)","2","mstr_standard","I262";
;
CDS_LIB"mstr_standard"
BODY_TYPE"PLUMBING"
HDL_TAP"TRUE";
"B \NAC \NWC"7;
"S \NAC"
BN"0"57;
%"TAP"
"1","(-5675,5100)","2","mstr_standard","I263";
;
CDS_LIB"mstr_standard"
BODY_TYPE"PLUMBING"
HDL_TAP"TRUE";
"B \NAC \NWC"5;
"S \NAC"
BN"9"56;
%"TAP"
"1","(-5675,4850)","2","mstr_standard","I264";
;
CDS_LIB"mstr_standard"
BODY_TYPE"PLUMBING"
HDL_TAP"TRUE";
"B \NAC \NWC"7;
"S \NAC"
BN"1"58;
%"TAP"
"1","(-5675,4750)","2","mstr_standard","I265";
;
CDS_LIB"mstr_standard"
BODY_TYPE"PLUMBING"
HDL_TAP"TRUE";
"B \NAC \NWC"7;
"S \NAC"
BN"2"59;
%"TAP"
"1","(-5675,4650)","2","mstr_standard","I266";
;
CDS_LIB"mstr_standard"
BODY_TYPE"PLUMBING"
HDL_TAP"TRUE";
"B \NAC \NWC"7;
"S \NAC"
BN"3"60;
%"TAP"
"1","(-5875,4900)","2","mstr_standard","I267";
;
CDS_LIB"mstr_standard"
BODY_TYPE"PLUMBING"
HDL_TAP"TRUE";
"B \NAC \NWC"8;
"S \NAC"
BN"0"42;
%"TAP"
"1","(-5875,5050)","2","mstr_standard","I268";
;
CDS_LIB"mstr_standard"
BODY_TYPE"PLUMBING"
HDL_TAP"TRUE";
"B \NAC \NWC"6;
"S \NAC"
BN"9"43;
%"TAP"
"1","(-5875,4800)","2","mstr_standard","I269";
;
CDS_LIB"mstr_standard"
BODY_TYPE"PLUMBING"
HDL_TAP"TRUE";
"B \NAC \NWC"8;
"S \NAC"
BN"1"44;
%"TAP"
"1","(-5875,4700)","2","mstr_standard","I270";
;
CDS_LIB"mstr_standard"
BODY_TYPE"PLUMBING"
HDL_TAP"TRUE";
"B \NAC \NWC"8;
"S \NAC"
BN"2"45;
%"TAP"
"1","(-5675,4550)","2","mstr_standard","I271";
;
CDS_LIB"mstr_standard"
BODY_TYPE"PLUMBING"
HDL_TAP"TRUE";
"B \NAC \NWC"7;
"S \NAC"
BN"4"52;
%"TAP"
"1","(-5675,4450)","2","mstr_standard","I272";
;
CDS_LIB"mstr_standard"
BODY_TYPE"PLUMBING"
HDL_TAP"TRUE";
"B \NAC \NWC"7;
"S \NAC"
BN"5"51;
%"TAP"
"1","(-5875,4600)","2","mstr_standard","I273";
;
CDS_LIB"mstr_standard"
BODY_TYPE"PLUMBING"
HDL_TAP"TRUE";
"B \NAC \NWC"8;
"S \NAC"
BN"3"46;
%"TAP"
"1","(-5675,4350)","2","mstr_standard","I274";
;
CDS_LIB"mstr_standard"
BODY_TYPE"PLUMBING"
HDL_TAP"TRUE";
"B \NAC \NWC"7;
"S \NAC"
BN"6"53;
%"TAP"
"1","(-5675,4250)","2","mstr_standard","I275";
;
CDS_LIB"mstr_standard"
BODY_TYPE"PLUMBING"
HDL_TAP"TRUE";
"B \NAC \NWC"7;
"S \NAC"
BN"7"54;
%"TAP"
"1","(-5675,4150)","2","mstr_standard","I276";
;
CDS_LIB"mstr_standard"
BODY_TYPE"PLUMBING"
HDL_TAP"TRUE";
"B \NAC \NWC"7;
"S \NAC"
BN"8"55;
%"TAP"
"1","(-5875,4400)","2","mstr_standard","I277";
;
CDS_LIB"mstr_standard"
BODY_TYPE"PLUMBING"
HDL_TAP"TRUE";
"B \NAC \NWC"8;
"S \NAC"
BN"5"47;
%"TAP"
"1","(-5875,4500)","2","mstr_standard","I278";
;
CDS_LIB"mstr_standard"
BODY_TYPE"PLUMBING"
HDL_TAP"TRUE";
"B \NAC \NWC"8;
"S \NAC"
BN"4"41;
%"TAP"
"1","(-5875,4100)","2","mstr_standard","I279";
;
CDS_LIB"mstr_standard"
BODY_TYPE"PLUMBING"
HDL_TAP"TRUE";
"B \NAC \NWC"8;
"S \NAC"
BN"8"50;
%"TAP"
"1","(-5875,4200)","2","mstr_standard","I280";
;
CDS_LIB"mstr_standard"
BODY_TYPE"PLUMBING"
HDL_TAP"TRUE";
"B \NAC \NWC"8;
"S \NAC"
BN"7"49;
%"TAP"
"1","(-5875,4300)","2","mstr_standard","I281";
;
CDS_LIB"mstr_standard"
BODY_TYPE"PLUMBING"
HDL_TAP"TRUE";
"B \NAC \NWC"8;
"S \NAC"
BN"6"48;
%"TAP"
"1","(-5675,4050)","2","mstr_standard","I286";
;
CDS_LIB"mstr_standard"
BODY_TYPE"PLUMBING"
HDL_TAP"TRUE";
"B \NAC \NWC"7;
"S \NAC"
BN"9"40;
%"TAP"
"1","(-5875,3850)","2","mstr_standard","I287";
;
CDS_LIB"mstr_standard"
BODY_TYPE"PLUMBING"
HDL_TAP"TRUE";
"B \NAC \NWC"10;
"S \NAC"
BN"0"27;
%"TAP"
"1","(-5875,4000)","2","mstr_standard","I288";
;
CDS_LIB"mstr_standard"
BODY_TYPE"PLUMBING"
HDL_TAP"TRUE";
"B \NAC \NWC"8;
"S \NAC"
BN"9"39;
%"TAP"
"1","(-5875,3700)","2","mstr_standard","I289";
;
CDS_LIB"mstr_standard"
BODY_TYPE"PLUMBING"
HDL_TAP"TRUE";
"B \NAC \NWC"10;
"S \NAC"
BN"3"30;
%"TAP"
"1","(-5875,3750)","2","mstr_standard","I290";
;
CDS_LIB"mstr_standard"
BODY_TYPE"PLUMBING"
HDL_TAP"TRUE";
"B \NAC \NWC"10;
"S \NAC"
BN"2"29;
%"TAP"
"1","(-5875,3800)","2","mstr_standard","I291";
;
CDS_LIB"mstr_standard"
BODY_TYPE"PLUMBING"
HDL_TAP"TRUE";
"B \NAC \NWC"10;
"S \NAC"
BN"1"28;
%"TAP"
"1","(-5875,3650)","2","mstr_standard","I292";
;
CDS_LIB"mstr_standard"
BODY_TYPE"PLUMBING"
HDL_TAP"TRUE";
"B \NAC \NWC"10;
"S \NAC"
BN"4"31;
%"TAP"
"1","(-5875,3600)","2","mstr_standard","I293";
;
CDS_LIB"mstr_standard"
BODY_TYPE"PLUMBING"
HDL_TAP"TRUE";
"B \NAC \NWC"10;
"S \NAC"
BN"5"25;
%"TAP"
"1","(-5875,3400)","2","mstr_standard","I294";
;
CDS_LIB"mstr_standard"
BODY_TYPE"PLUMBING"
HDL_TAP"TRUE";
"B \NAC \NWC"9;
"S \NAC"
BN"1"33;
%"TAP"
"1","(-5875,3350)","2","mstr_standard","I295";
;
CDS_LIB"mstr_standard"
BODY_TYPE"PLUMBING"
HDL_TAP"TRUE";
"B \NAC \NWC"9;
"S \NAC"
BN"2"34;
%"TAP"
"1","(-5875,3450)","2","mstr_standard","I296";
;
CDS_LIB"mstr_standard"
BODY_TYPE"PLUMBING"
HDL_TAP"TRUE";
"B \NAC \NWC"9;
"S \NAC"
BN"0"32;
%"TAP"
"1","(-5875,3550)","2","mstr_standard","I297";
;
CDS_LIB"mstr_standard"
BODY_TYPE"PLUMBING"
HDL_TAP"TRUE";
"B \NAC \NWC"10;
"S \NAC"
BN"6"26;
%"TAP"
"1","(-5875,3200)","2","mstr_standard","I298";
;
CDS_LIB"mstr_standard"
BODY_TYPE"PLUMBING"
HDL_TAP"TRUE";
"B \NAC \NWC"9;
"S \NAC"
BN"5"37;
%"TAP"
"1","(-5875,3150)","2","mstr_standard","I299";
;
CDS_LIB"mstr_standard"
BODY_TYPE"PLUMBING"
HDL_TAP"TRUE";
"B \NAC \NWC"9;
"S \NAC"
BN"6"38;
%"TAP"
"1","(-5875,3250)","2","mstr_standard","I300";
;
CDS_LIB"mstr_standard"
BODY_TYPE"PLUMBING"
HDL_TAP"TRUE";
"B \NAC \NWC"9;
"S \NAC"
BN"4"36;
%"TAP"
"1","(-5875,3300)","2","mstr_standard","I301";
;
CDS_LIB"mstr_standard"
BODY_TYPE"PLUMBING"
HDL_TAP"TRUE";
"B \NAC \NWC"9;
"S \NAC"
BN"3"35;
%"Q_RES"
"1","(-6800,2150)","0","pure_quanta","I314";
;
LOCATION"R384"
$SEC"1"
CDS_SEC"1"
PACK_TYPE"0402LF"
TOLERANCE"1%"
VALUE"15"
MATERIAL"CHIP"
WATTAGE"1/16W"
CDS_LIB"pure_quanta"
PART_NUMBER"CS01502FB03";
"B"
$PN"2"12;
"A"
$PN"1"11;
END.
